(kicad_pcb
	(version 20260206)
	(generator "pcbnew")
	(generator_version "10.0")
	(general
		(thickness 1.6)
		(legacy_teardrops no)
	)
	(paper "A4")
	(title_block
		(title "03242023_DA0F0TMBIJ0_F0T_Motherboard_J_brd_V01_OCP.brd")
		(comment 1 "Grand Teton / footprints 5395-5400 of 6105")
	)
	(layers
		(0 "F.Cu" signal "TOP")
		(4 "In1.Cu" signal "GND")
		(6 "In2.Cu" signal "IN1")
		(8 "In3.Cu" signal "GND1")
		(10 "In4.Cu" signal "IN2")
		(12 "In5.Cu" signal "GND2")
		(14 "In6.Cu" signal "IN3")
		(16 "In7.Cu" signal "GND3")
		(18 "In8.Cu" signal "VCC")
		(20 "In9.Cu" signal "VCC1")
		(22 "In10.Cu" signal "GND4")
		(24 "In11.Cu" signal "IN4")
		(26 "In12.Cu" signal "GND5")
		(28 "In13.Cu" signal "IN5")
		(30 "In14.Cu" signal "GND6")
		(32 "In15.Cu" signal "IN6")
		(34 "In16.Cu" signal "GND7")
		(2 "B.Cu" signal "BOTTOM")
		(9 "F.Adhes" user "F.Adhesive")
		(11 "B.Adhes" user "B.Adhesive")
		(13 "F.Paste" user "Package Geometry/Pastemask Top")
		(15 "B.Paste" user "Package Geometry/Pastemask Bottom")
		(5 "F.SilkS" user "Ref Des/Silkscreen Top")
		(7 "B.SilkS" user "Ref Des/Silkscreen Bottom")
		(1 "F.Mask" user "Board Geometry/Soldermask Top")
		(3 "B.Mask" user "Board Geometry/Soldermask Bottom")
		(17 "Dwgs.User" user "User.Drawings")
		(19 "Cmts.User" user "User.Comments")
		(21 "Eco1.User" user "User.Eco1")
		(23 "Eco2.User" user "User.Eco2")
		(25 "Edge.Cuts" user "Board Geometry/Outline")
		(27 "Margin" user)
		(31 "F.CrtYd" user "Package Geometry/Place Bound Top")
		(29 "B.CrtYd" user "Package Geometry/Place Bound Bottom")
		(35 "F.Fab" user "Ref Des/Assembly Top")
		(33 "B.Fab" user "Ref Des/Assembly Bottom")
	)
	(footprint ""
		(layer "B.Cu")
		(at 303.959768 -365.219488 180)
		(property "Reference" "PC1672"
			(at 0 0 0)
			(layer "B.SilkS")
			(hide yes)
			(effects
				(font
					(size 1.27 1.27)
				)
				(justify mirror)
			)
		)
		(property "Value" ""
			(at 0 0 0)
			(layer "B.Fab")
			(effects
				(font
					(size 1.27 1.27)
				)
				(justify mirror)
			)
		)
		(duplicate_pad_numbers_are_jumpers no)
		(fp_line
			(start 1.524 0.762)
			(end 1.524 -0.762)
			(stroke
				(width 0.1524)
				(type default)
			)
			(layer "B.SilkS")
		)
		(fp_line
			(start 1.524 -0.762)
			(end -1.524 -0.762)
			(stroke
				(width 0.1524)
				(type default)
			)
			(layer "B.SilkS")
		)
		(fp_line
			(start -1.524 0.762)
			(end 1.524 0.762)
			(stroke
				(width 0.1524)
				(type default)
			)
			(layer "B.SilkS")
		)
		(fp_line
			(start -1.524 -0.762)
			(end -1.524 0.762)
			(stroke
				(width 0.1524)
				(type default)
			)
			(layer "B.SilkS")
		)
		(fp_line
			(start 1.1049 0.724916)
			(end -1.1049 0.724916)
			(stroke
				(width 0.1)
				(type default)
			)
			(layer "B.Fab")
		)
		(fp_line
			(start 1.1049 -0.724916)
			(end 1.1049 0.724916)
			(stroke
				(width 0.1)
				(type default)
			)
			(layer "B.Fab")
		)
		(fp_line
			(start -1.1049 0.724916)
			(end -1.1049 -0.724916)
			(stroke
				(width 0.1)
				(type default)
			)
			(layer "B.Fab")
		)
		(fp_line
			(start -1.1049 -0.724916)
			(end 1.1049 -0.724916)
			(stroke
				(width 0.1)
				(type default)
			)
			(layer "B.Fab")
		)
		(pad "1" smd rect
			(at 0.889 0 180)
			(size 1.016 1.27)
			(layers "B.Cu" "B.Mask" "B.Paste")
			(net "SW_P12V_PVCCFA_EHV_FIVRA_CPU0_L")
		)
		(pad "2" smd rect
			(at -0.889 0 180)
			(size 1.016 1.27)
			(layers "B.Cu" "B.Mask" "B.Paste")
			(net "GND")
		)
	)
	(footprint ""
		(layer "B.Cu")
		(at 344.820748 -32.58439 180)
		(property "Reference" "R1962"
			(at 0 0 0)
			(layer "B.SilkS")
			(hide yes)
			(effects
				(font
					(size 1.27 1.27)
				)
				(justify mirror)
			)
		)
		(property "Value" ""
			(at 0 0 0)
			(layer "B.Fab")
			(effects
				(font
					(size 1.27 1.27)
				)
				(justify mirror)
			)
		)
		(duplicate_pad_numbers_are_jumpers no)
		(fp_line
			(start 0.7874 0.4064)
			(end 0.7874 -0.4064)
			(stroke
				(width 0.1524)
				(type default)
			)
			(layer "B.SilkS")
		)
		(fp_line
			(start 0.7874 -0.4064)
			(end -0.7874 -0.4064)
			(stroke
				(width 0.1524)
				(type default)
			)
			(layer "B.SilkS")
		)
		(fp_line
			(start -0.7874 0.4064)
			(end 0.7874 0.4064)
			(stroke
				(width 0.1524)
				(type default)
			)
			(layer "B.SilkS")
		)
		(fp_line
			(start -0.7874 -0.4064)
			(end -0.7874 0.4064)
			(stroke
				(width 0.1524)
				(type default)
			)
			(layer "B.SilkS")
		)
		(fp_line
			(start 0.67945 0.3048)
			(end 0.67945 -0.305054)
			(stroke
				(width 0.1)
				(type default)
			)
			(layer "B.Fab")
		)
		(fp_line
			(start 0.67945 -0.305054)
			(end 0.12065 -0.305054)
			(stroke
				(width 0.1)
				(type default)
			)
			(layer "B.Fab")
		)
		(fp_line
			(start 0.12065 0.3048)
			(end 0.67945 0.3048)
			(stroke
				(width 0.1)
				(type default)
			)
			(layer "B.Fab")
		)
		(fp_line
			(start 0.12065 0.2794)
			(end 0.12065 0.3048)
			(stroke
				(width 0.1)
				(type default)
			)
			(layer "B.Fab")
		)
		(fp_line
			(start 0.12065 -0.2794)
			(end -0.12065 -0.2794)
			(stroke
				(width 0.1)
				(type default)
			)
			(layer "B.Fab")
		)
		(fp_line
			(start 0.12065 -0.305054)
			(end 0.12065 -0.2794)
			(stroke
				(width 0.1)
				(type default)
			)
			(layer "B.Fab")
		)
		(fp_line
			(start -0.120396 0.3048)
			(end -0.120396 0.2794)
			(stroke
				(width 0.1)
				(type default)
			)
			(layer "B.Fab")
		)
		(fp_line
			(start -0.120396 0.2794)
			(end 0.12065 0.2794)
			(stroke
				(width 0.1)
				(type default)
			)
			(layer "B.Fab")
		)
		(fp_line
			(start -0.12065 -0.2794)
			(end -0.12065 -0.3048)
			(stroke
				(width 0.1)
				(type default)
			)
			(layer "B.Fab")
		)
		(fp_line
			(start -0.12065 -0.3048)
			(end -0.67945 -0.3048)
			(stroke
				(width 0.1)
				(type default)
			)
			(layer "B.Fab")
		)
		(fp_line
			(start -0.67945 0.3048)
			(end -0.120396 0.3048)
			(stroke
				(width 0.1)
				(type default)
			)
			(layer "B.Fab")
		)
		(fp_line
			(start -0.67945 -0.3048)
			(end -0.67945 0.3048)
			(stroke
				(width 0.1)
				(type default)
			)
			(layer "B.Fab")
		)
		(pad "1" smd circle
			(at 0.40005 0)
			(size 0 0)
			(layers "B.Cu" "B.Mask" "B.Paste")
			(net "FM_PCH_CONSENT_STRAP_N")
		)
		(pad "2" smd circle
			(at -0.40005 0)
			(size 0 0)
			(layers "B.Cu" "B.Mask" "B.Paste")
			(net "GND")
		)
	)
	(footprint ""
		(layer "B.Cu")
		(at 52.335684 -161.260028)
		(property "Reference" "PR1805"
			(at 0 0 0)
			(layer "B.SilkS")
			(hide yes)
			(effects
				(font
					(size 1.27 1.27)
				)
				(justify mirror)
			)
		)
		(property "Value" ""
			(at 0 0 0)
			(layer "B.Fab")
			(effects
				(font
					(size 1.27 1.27)
				)
				(justify mirror)
			)
		)
		(duplicate_pad_numbers_are_jumpers no)
		(fp_line
			(start -0.7874 -0.4064)
			(end -0.7874 0.4064)
			(stroke
				(width 0.1524)
				(type default)
			)
			(layer "B.SilkS")
		)
		(fp_line
			(start -0.7874 0.4064)
			(end 0.7874 0.4064)
			(stroke
				(width 0.1524)
				(type default)
			)
			(layer "B.SilkS")
		)
		(fp_line
			(start 0.7874 -0.4064)
			(end -0.7874 -0.4064)
			(stroke
				(width 0.1524)
				(type default)
			)
			(layer "B.SilkS")
		)
		(fp_line
			(start 0.7874 0.4064)
			(end 0.7874 -0.4064)
			(stroke
				(width 0.1524)
				(type default)
			)
			(layer "B.SilkS")
		)
		(fp_line
			(start -0.67945 -0.3048)
			(end -0.67945 0.3048)
			(stroke
				(width 0.1)
				(type default)
			)
			(layer "B.Fab")
		)
		(fp_line
			(start -0.67945 0.3048)
			(end -0.120396 0.3048)
			(stroke
				(width 0.1)
				(type default)
			)
			(layer "B.Fab")
		)
		(fp_line
			(start -0.12065 -0.3048)
			(end -0.67945 -0.3048)
			(stroke
				(width 0.1)
				(type default)
			)
			(layer "B.Fab")
		)
		(fp_line
			(start -0.12065 -0.2794)
			(end -0.12065 -0.3048)
			(stroke
				(width 0.1)
				(type default)
			)
			(layer "B.Fab")
		)
		(fp_line
			(start -0.120396 0.2794)
			(end 0.12065 0.2794)
			(stroke
				(width 0.1)
				(type default)
			)
			(layer "B.Fab")
		)
		(fp_line
			(start -0.120396 0.3048)
			(end -0.120396 0.2794)
			(stroke
				(width 0.1)
				(type default)
			)
			(layer "B.Fab")
		)
		(fp_line
			(start 0.12065 -0.305054)
			(end 0.12065 -0.2794)
			(stroke
				(width 0.1)
				(type default)
			)
			(layer "B.Fab")
		)
		(fp_line
			(start 0.12065 -0.2794)
			(end -0.12065 -0.2794)
			(stroke
				(width 0.1)
				(type default)
			)
			(layer "B.Fab")
		)
		(fp_line
			(start 0.12065 0.2794)
			(end 0.12065 0.3048)
			(stroke
				(width 0.1)
				(type default)
			)
			(layer "B.Fab")
		)
		(fp_line
			(start 0.12065 0.3048)
			(end 0.67945 0.3048)
			(stroke
				(width 0.1)
				(type default)
			)
			(layer "B.Fab")
		)
		(fp_line
			(start 0.67945 -0.305054)
			(end 0.12065 -0.305054)
			(stroke
				(width 0.1)
				(type default)
			)
			(layer "B.Fab")
		)
		(fp_line
			(start 0.67945 0.3048)
			(end 0.67945 -0.305054)
			(stroke
				(width 0.1)
				(type default)
			)
			(layer "B.Fab")
		)
		(pad "1" smd circle
			(at 0.40005 0 180)
			(size 0 0)
			(layers "B.Cu" "B.Mask" "B.Paste")
			(net "PVCCD_HV_CPU1_VOS")
		)
		(pad "2" smd circle
			(at -0.40005 0 180)
			(size 0 0)
			(layers "B.Cu" "B.Mask" "B.Paste")
			(net "PVCCD_HV_CPU1")
		)
	)
	(footprint ""
		(layer "B.Cu")
		(at 338.911692 -187.998608 -90)
		(property "Reference" "R4"
			(at 0 0 90)
			(layer "B.SilkS")
			(hide yes)
			(effects
				(font
					(size 1.27 1.27)
				)
				(justify mirror)
			)
		)
		(property "Value" ""
			(at 0 0 90)
			(layer "B.Fab")
			(effects
				(font
					(size 1.27 1.27)
				)
				(justify mirror)
			)
		)
		(duplicate_pad_numbers_are_jumpers no)
		(fp_line
			(start -0.7874 0.4064)
			(end 0.7874 0.4064)
			(stroke
				(width 0.1524)
				(type default)
			)
			(layer "B.SilkS")
		)
		(fp_line
			(start 0.7874 0.4064)
			(end 0.7874 -0.4064)
			(stroke
				(width 0.1524)
				(type default)
			)
			(layer "B.SilkS")
		)
		(fp_line
			(start -0.7874 -0.4064)
			(end -0.7874 0.4064)
			(stroke
				(width 0.1524)
				(type default)
			)
			(layer "B.SilkS")
		)
		(fp_line
			(start 0.7874 -0.4064)
			(end -0.7874 -0.4064)
			(stroke
				(width 0.1524)
				(type default)
			)
			(layer "B.SilkS")
		)
		(fp_line
			(start -0.67945 0.3048)
			(end -0.120396 0.3048)
			(stroke
				(width 0.1)
				(type default)
			)
			(layer "B.Fab")
		)
		(fp_line
			(start -0.120396 0.3048)
			(end -0.120396 0.2794)
			(stroke
				(width 0.1)
				(type default)
			)
			(layer "B.Fab")
		)
		(fp_line
			(start 0.12065 0.3048)
			(end 0.67945 0.3048)
			(stroke
				(width 0.1)
				(type default)
			)
			(layer "B.Fab")
		)
		(fp_line
			(start 0.67945 0.3048)
			(end 0.67945 -0.305054)
			(stroke
				(width 0.1)
				(type default)
			)
			(layer "B.Fab")
		)
		(fp_line
			(start -0.120396 0.2794)
			(end 0.12065 0.2794)
			(stroke
				(width 0.1)
				(type default)
			)
			(layer "B.Fab")
		)
		(fp_line
			(start 0.12065 0.2794)
			(end 0.12065 0.3048)
			(stroke
				(width 0.1)
				(type default)
			)
			(layer "B.Fab")
		)
		(fp_line
			(start -0.12065 -0.2794)
			(end -0.12065 -0.3048)
			(stroke
				(width 0.1)
				(type default)
			)
			(layer "B.Fab")
		)
		(fp_line
			(start 0.12065 -0.2794)
			(end -0.12065 -0.2794)
			(stroke
				(width 0.1)
				(type default)
			)
			(layer "B.Fab")
		)
		(fp_line
			(start -0.67945 -0.3048)
			(end -0.67945 0.3048)
			(stroke
				(width 0.1)
				(type default)
			)
			(layer "B.Fab")
		)
		(fp_line
			(start -0.12065 -0.3048)
			(end -0.67945 -0.3048)
			(stroke
				(width 0.1)
				(type default)
			)
			(layer "B.Fab")
		)
		(fp_line
			(start 0.12065 -0.305054)
			(end 0.12065 -0.2794)
			(stroke
				(width 0.1)
				(type default)
			)
			(layer "B.Fab")
		)
		(fp_line
			(start 0.67945 -0.305054)
			(end 0.12065 -0.305054)
			(stroke
				(width 0.1)
				(type default)
			)
			(layer "B.Fab")
		)
		(pad "1" smd circle
			(at 0.40005 0 90)
			(size 0 0)
			(layers "B.Cu" "B.Mask" "B.Paste")
			(net "JTAG_MUX_CPU0_GTL_TDI")
		)
		(pad "2" smd circle
			(at -0.40005 0 90)
			(size 0 0)
			(layers "B.Cu" "B.Mask" "B.Paste")
			(net "JTAG_DBP_CPU0_GTL_R_TDI")
		)
	)
	(footprint ""
		(layer "B.Cu")
		(at 104.786938 -236.00791 180)
		(property "Reference" "C71"
			(at 0 0 0)
			(layer "B.SilkS")
			(hide yes)
			(effects
				(font
					(size 1.27 1.27)
				)
				(justify mirror)
			)
		)
		(property "Value" ""
			(at 0 0 0)
			(layer "B.Fab")
			(effects
				(font
					(size 1.27 1.27)
				)
				(justify mirror)
			)
		)
		(duplicate_pad_numbers_are_jumpers no)
		(fp_line
			(start 0.7874 0.4064)
			(end 0.7874 -0.4064)
			(stroke
				(width 0.1524)
				(type default)
			)
			(layer "B.SilkS")
		)
		(fp_line
			(start 0.7874 -0.4064)
			(end -0.7874 -0.4064)
			(stroke
				(width 0.1524)
				(type default)
			)
			(layer "B.SilkS")
		)
		(fp_line
			(start -0.7874 0.4064)
			(end 0.7874 0.4064)
			(stroke
				(width 0.1524)
				(type default)
			)
			(layer "B.SilkS")
		)
		(fp_line
			(start -0.7874 -0.4064)
			(end -0.7874 0.4064)
			(stroke
				(width 0.1524)
				(type default)
			)
			(layer "B.SilkS")
		)
		(fp_line
			(start 0.67945 0.3048)
			(end 0.67945 -0.305054)
			(stroke
				(width 0.1)
				(type default)
			)
			(layer "B.Fab")
		)
		(fp_line
			(start 0.67945 -0.305054)
			(end 0.12065 -0.305054)
			(stroke
				(width 0.1)
				(type default)
			)
			(layer "B.Fab")
		)
		(fp_line
			(start 0.12065 0.3048)
			(end 0.67945 0.3048)
			(stroke
				(width 0.1)
				(type default)
			)
			(layer "B.Fab")
		)
		(fp_line
			(start 0.12065 0.2794)
			(end 0.12065 0.3048)
			(stroke
				(width 0.1)
				(type default)
			)
			(layer "B.Fab")
		)
		(fp_line
			(start 0.12065 -0.2794)
			(end -0.12065 -0.2794)
			(stroke
				(width 0.1)
				(type default)
			)
			(layer "B.Fab")
		)
		(fp_line
			(start 0.12065 -0.305054)
			(end 0.12065 -0.2794)
			(stroke
				(width 0.1)
				(type default)
			)
			(layer "B.Fab")
		)
		(fp_line
			(start -0.120396 0.3048)
			(end -0.120396 0.2794)
			(stroke
				(width 0.1)
				(type default)
			)
			(layer "B.Fab")
		)
		(fp_line
			(start -0.120396 0.2794)
			(end 0.12065 0.2794)
			(stroke
				(width 0.1)
				(type default)
			)
			(layer "B.Fab")
		)
		(fp_line
			(start -0.12065 -0.2794)
			(end -0.12065 -0.3048)
			(stroke
				(width 0.1)
				(type default)
			)
			(layer "B.Fab")
		)
		(fp_line
			(start -0.12065 -0.3048)
			(end -0.67945 -0.3048)
			(stroke
				(width 0.1)
				(type default)
			)
			(layer "B.Fab")
		)
		(fp_line
			(start -0.67945 0.3048)
			(end -0.120396 0.3048)
			(stroke
				(width 0.1)
				(type default)
			)
			(layer "B.Fab")
		)
		(fp_line
			(start -0.67945 -0.3048)
			(end -0.67945 0.3048)
			(stroke
				(width 0.1)
				(type default)
			)
			(layer "B.Fab")
		)
		(pad "1" smd circle
			(at 0.40005 0)
			(size 0 0)
			(layers "B.Cu" "B.Mask" "B.Paste")
			(net "P3V3_AUX")
		)
		(pad "2" smd circle
			(at -0.40005 0)
			(size 0 0)
			(layers "B.Cu" "B.Mask" "B.Paste")
			(net "GND")
		)
	)
	(footprint ""
		(layer "B.Cu")
		(at 128.86944 -36.751768 90)
		(property "Reference" "R4274"
			(at 0 0 90)
			(layer "B.SilkS")
			(hide yes)
			(effects
				(font
					(size 1.27 1.27)
				)
				(justify mirror)
			)
		)
		(property "Value" ""
			(at 0 0 90)
			(layer "B.Fab")
			(effects
				(font
					(size 1.27 1.27)
				)
				(justify mirror)
			)
		)
		(duplicate_pad_numbers_are_jumpers no)
		(fp_line
			(start 0.7874 -0.4064)
			(end -0.7874 -0.4064)
			(stroke
				(width 0.1524)
				(type default)
			)
			(layer "B.SilkS")
		)
		(fp_line
			(start -0.7874 -0.4064)
			(end -0.7874 0.4064)
			(stroke
				(width 0.1524)
				(type default)
			)
			(layer "B.SilkS")
		)
		(fp_line
			(start 0.7874 0.4064)
			(end 0.7874 -0.4064)
			(stroke
				(width 0.1524)
				(type default)
			)
			(layer "B.SilkS")
		)
		(fp_line
			(start -0.7874 0.4064)
			(end 0.7874 0.4064)
			(stroke
				(width 0.1524)
				(type default)
			)
			(layer "B.SilkS")
		)
		(fp_line
			(start 0.67945 -0.305054)
			(end 0.12065 -0.305054)
			(stroke
				(width 0.1)
				(type default)
			)
			(layer "B.Fab")
		)
		(fp_line
			(start 0.12065 -0.305054)
			(end 0.12065 -0.2794)
			(stroke
				(width 0.1)
				(type default)
			)
			(layer "B.Fab")
		)
		(fp_line
			(start -0.12065 -0.3048)
			(end -0.67945 -0.3048)
			(stroke
				(width 0.1)
				(type default)
			)
			(layer "B.Fab")
		)
		(fp_line
			(start -0.67945 -0.3048)
			(end -0.67945 0.3048)
			(stroke
				(width 0.1)
				(type default)
			)
			(layer "B.Fab")
		)
		(fp_line
			(start 0.12065 -0.2794)
			(end -0.12065 -0.2794)
			(stroke
				(width 0.1)
				(type default)
			)
			(layer "B.Fab")
		)
		(fp_line
			(start -0.12065 -0.2794)
			(end -0.12065 -0.3048)
			(stroke
				(width 0.1)
				(type default)
			)
			(layer "B.Fab")
		)
		(fp_line
			(start 0.12065 0.2794)
			(end 0.12065 0.3048)
			(stroke
				(width 0.1)
				(type default)
			)
			(layer "B.Fab")
		)
		(fp_line
			(start -0.120396 0.2794)
			(end 0.12065 0.2794)
			(stroke
				(width 0.1)
				(type default)
			)
			(layer "B.Fab")
		)
		(fp_line
			(start 0.67945 0.3048)
			(end 0.67945 -0.305054)
			(stroke
				(width 0.1)
				(type default)
			)
			(layer "B.Fab")
		)
		(fp_line
			(start 0.12065 0.3048)
			(end 0.67945 0.3048)
			(stroke
				(width 0.1)
				(type default)
			)
			(layer "B.Fab")
		)
		(fp_line
			(start -0.120396 0.3048)
			(end -0.120396 0.2794)
			(stroke
				(width 0.1)
				(type default)
			)
			(layer "B.Fab")
		)
		(fp_line
			(start -0.67945 0.3048)
			(end -0.120396 0.3048)
			(stroke
				(width 0.1)
				(type default)
			)
			(layer "B.Fab")
		)
		(pad "1" smd circle
			(at 0.40005 0 270)
			(size 0 0)
			(layers "B.Cu" "B.Mask" "B.Paste")
			(net "FM_USB3_1_FGB")
		)
		(pad "2" smd circle
			(at -0.40005 0 270)
			(size 0 0)
			(layers "B.Cu" "B.Mask" "B.Paste")
			(net "GND")
		)
	)
)
